FILE_TYPE = MULTI_PHYS_TABLE;
PART 'VERT_BATT_3PIN'
{========================================================================================}
:PACK_TYPE | MATERIAL | PART_NUMBER     = ENVCOMP                  | PART_NUMBER  | JEDEC_TYPE           | CLASS      | DESCRIPTION                      | HEIGHT     | COMPONENT_TYPE | LEAD_LENGTH | LPID | SPEED_URL                                                                                                                       | STATUS     | RPL   | AML | BUS_UNIT     | DAYS  ;
{========================================================================================}
'TH'      | '3PVERT' | 'C68619-005'(!) = ''                       | 'C68619-005' | 'VERT_BATT_3PIN'     | 'DISCRETE' | 'BAT ACC,HOLDR,THM,CR2032'       | '0.526 IN' | 'THMT'         | '0.122'     | ''   | 'http://speed.intel.com:8081/speed/module/pdm/item/pdm_item_detail_direct.asp?item_cde=C68619-005&item_rev=01&url_param=unused' | ''         | ''    | ''  | ''           | ''   
'TH'      | 'EMPTY'  | 'C68619-005'(!) = ''                       | 'C68619-005' | 'VERT_BATT_3PIN'     | 'IO'       | 'BAT ACC,HOLDR,THM,CR2032'       | '0.526 IN' | 'THMT'         | '0.122'     | ''   | 'http://speed.intel.com:8081/speed/module/pdm/item/pdm_item_detail_direct.asp?item_cde=C68619-005&item_rev=01&url_param=unused' | ''         | ''    | ''  | ''           | ''   
'PIP'     | '3PVERT' | 'C68619-005'(!) = ''                       | 'C68619-005' | 'VERT_BATT_3PIN_PIP' | 'DISCRETE' | 'BAT ACC,HOLDR,THM,CR2032'       | '0.526 IN' | 'THMT'         | '0.122'     | ''   | 'http://speed.intel.com:8081/speed/module/pdm/item/pdm_item_detail_direct.asp?item_cde=C68619-005&item_rev=01&url_param=unused' | ''         | ''    | ''  | ''           | ''   
'PIP'     | 'EMPTY'  | 'C68619-005'(!) = ''                       | 'C68619-005' | 'VERT_BATT_3PIN_PIP' | 'IO'       | 'BAT ACC,HOLDR,THM,CR2032'       | '0.526 IN' | 'THMT'         | '0.122'     | ''   | 'http://speed.intel.com:8081/speed/module/pdm/item/pdm_item_detail_direct.asp?item_cde=C68619-005&item_rev=01&url_param=unused' | ''         | ''    | ''  | ''           | ''   
END_PART
END.
